(kicad_pcb
	(version 20260206)
	(generator "pcbnew")
	(generator_version "10.0")
	(general
		(thickness 1.6)
		(legacy_teardrops no)
	)
	(paper "A4")
	(title_block
		(title "baseboard — 13948-1b.1110WZS1818.brd")
		(comment 1 "Honey Badger (Wiwynn) / footprints 567-574 of 2523")
	)
	(layers
		(0 "F.Cu" signal "TOP")
		(4 "In1.Cu" signal "L2GND")
		(6 "In2.Cu" signal "L3")
		(8 "In3.Cu" signal "L4VCC")
		(10 "In4.Cu" signal "L5VCC")
		(12 "In5.Cu" signal "L6")
		(14 "In6.Cu" signal "L7GND")
		(2 "B.Cu" signal "BOTTOM")
		(9 "F.Adhes" user "F.Adhesive")
		(11 "B.Adhes" user "B.Adhesive")
		(13 "F.Paste" user "Package Geometry/Pastemask Top")
		(15 "B.Paste" user "Package Geometry/Pastemask Bottom")
		(5 "F.SilkS" user "Ref Des/Silkscreen Top")
		(7 "B.SilkS" user "Ref Des/Silkscreen Bottom")
		(1 "F.Mask" user "Board Geometry/Soldermask Top")
		(3 "B.Mask" user "Board Geometry/Soldermask Bottom")
		(17 "Dwgs.User" user "User.Drawings")
		(19 "Cmts.User" user "User.Comments")
		(21 "Eco1.User" user "User.Eco1")
		(23 "Eco2.User" user "User.Eco2")
		(25 "Edge.Cuts" user "Board Geometry/Outline")
		(27 "Margin" user)
		(31 "F.CrtYd" user "Package Geometry/Place Bound Top")
		(29 "B.CrtYd" user "Package Geometry/Place Bound Bottom")
		(35 "F.Fab" user "Ref Des/Assembly Top")
		(33 "B.Fab" user "Ref Des/Assembly Bottom")
	)
	(footprint ""
		(layer "F.Cu")
		(at 222.758 -157.282388)
		(property "Reference" "Q17"
			(at 0 0 0)
			(layer "F.SilkS")
			(hide yes)
			(effects
				(font
					(size 1.27 1.27)
				)
			)
		)
		(property "Value" "2N7002A-7-GP"
			(at 0.127 -8.9662 0)
			(unlocked yes)
			(layer "F.Fab")
			(hide yes)
			(effects
				(font
					(size 1.016 1.016)
					(thickness 0.1524)
				)
			)
		)
		(property "Device Type" "SOT23DGS2D4H48"
			(at 0.127 -10.4902 0)
			(unlocked yes)
			(layer "F.Fab")
			(hide yes)
			(effects
				(font
					(size 1.016 1.016)
					(thickness 0.1524)
				)
			)
		)
		(duplicate_pad_numbers_are_jumpers no)
		(fp_line
			(start -1.651 -1.778)
			(end -1.651 1.778)
			(stroke
				(width 0.1524)
				(type default)
			)
			(layer "F.SilkS")
		)
		(fp_line
			(start -1.651 1.778)
			(end 1.651 1.778)
			(stroke
				(width 0.1524)
				(type default)
			)
			(layer "F.SilkS")
		)
		(fp_line
			(start 1.651 -1.778)
			(end -1.651 -1.778)
			(stroke
				(width 0.1524)
				(type default)
			)
			(layer "F.SilkS")
		)
		(fp_line
			(start 1.651 1.778)
			(end 1.651 -1.778)
			(stroke
				(width 0.1524)
				(type default)
			)
			(layer "F.SilkS")
		)
		(fp_poly
			(pts
				(xy -1.778 1.8796) (xy -1.778 -1.8796) (xy 1.778 -1.8796) (xy 1.778 1.8796)
			)
			(stroke
				(width 0)
				(type default)
			)
			(fill no)
			(layer "F.CrtYd")
		)
		(fp_poly
			(pts
				(xy -1.778 1.8796) (xy -1.778 -1.8796) (xy 1.778 -1.8796) (xy 1.778 1.8796)
			)
			(stroke
				(width 0)
				(type default)
			)
			(fill no)
			(layer "F.Fab")
		)
		(pad "D" smd custom
			(at 0 -0.9525)
			(size 0.1905 0.1905)
			(layers "F.Cu" "F.Mask" "F.Paste")
			(net "JTAG_DT")
			(options
				(clearance outline)
				(anchor circle)
			)
			(primitives
				(gr_poly
					(pts
						(arc
							(start -0.1778 0.5715)
							(mid -0.321484 0.511984)
							(end -0.381 0.3683)
						)
						(arc
							(start -0.381 -0.3683)
							(mid -0.321484 -0.511984)
							(end -0.1778 -0.5715)
						)
						(arc
							(start 0.1778 -0.5715)
							(mid 0.321484 -0.511984)
							(end 0.381 -0.3683)
						)
						(arc
							(start 0.381 0.3683)
							(mid 0.321484 0.511984)
							(end 0.1778 0.5715)
						)
					)
					(width 0)
					(fill yes)
				)
			)
		)
		(pad "G" smd custom
			(at -0.98425 0.9525)
			(size 0.1905 0.1905)
			(layers "F.Cu" "F.Mask" "F.Paste")
			(net "BMC_JTAG_L")
			(options
				(clearance outline)
				(anchor circle)
			)
			(primitives
				(gr_poly
					(pts
						(arc
							(start -0.1778 0.5715)
							(mid -0.321484 0.511984)
							(end -0.381 0.3683)
						)
						(arc
							(start -0.381 -0.3683)
							(mid -0.321484 -0.511984)
							(end -0.1778 -0.5715)
						)
						(arc
							(start 0.1778 -0.5715)
							(mid 0.321484 -0.511984)
							(end 0.381 -0.3683)
						)
						(arc
							(start 0.381 0.3683)
							(mid 0.321484 0.511984)
							(end 0.1778 0.5715)
						)
					)
					(width 0)
					(fill yes)
				)
			)
		)
		(pad "S" smd custom
			(at 0.98425 0.9525)
			(size 0.1905 0.1905)
			(layers "F.Cu" "F.Mask" "F.Paste")
			(net "GND")
			(options
				(clearance outline)
				(anchor circle)
			)
			(primitives
				(gr_poly
					(pts
						(arc
							(start -0.1778 0.5715)
							(mid -0.321484 0.511984)
							(end -0.381 0.3683)
						)
						(arc
							(start -0.381 -0.3683)
							(mid -0.321484 -0.511984)
							(end -0.1778 -0.5715)
						)
						(arc
							(start 0.1778 -0.5715)
							(mid 0.321484 -0.511984)
							(end 0.381 -0.3683)
						)
						(arc
							(start 0.381 0.3683)
							(mid 0.321484 0.511984)
							(end 0.1778 0.5715)
						)
					)
					(width 0)
					(fill yes)
				)
			)
		)
	)
	(footprint ""
		(layer "F.Cu")
		(at 348.390718 -143.233648)
		(property "Reference" "C158"
			(at 0 0 0)
			(layer "F.SilkS")
			(hide yes)
			(effects
				(font
					(size 1.27 1.27)
				)
			)
		)
		(property "Value" "SC1U10V2KX-4-GP"
			(at 1.1811 -2.7051 0)
			(unlocked yes)
			(layer "F.Fab")
			(hide yes)
			(effects
				(font
					(size 1.016 1.016)
					(thickness 0.1524)
				)
			)
		)
		(property "Device Type" "C402H22"
			(at 1.1811 -4.2291 0)
			(unlocked yes)
			(layer "F.Fab")
			(hide yes)
			(effects
				(font
					(size 1.016 1.016)
					(thickness 0.1524)
				)
			)
		)
		(duplicate_pad_numbers_are_jumpers no)
		(fp_rect
			(start -0.4318 0.9525)
			(end 0.4318 -0.9525)
			(stroke
				(width 0)
				(type default)
			)
			(fill no)
			(layer "F.CrtYd")
		)
		(fp_rect
			(start -0.4318 0.9525)
			(end 0.4318 -0.9525)
			(stroke
				(width 0)
				(type default)
			)
			(fill no)
			(layer "F.Fab")
		)
		(pad "1" smd custom
			(at 0 -0.4445)
			(size 0.1524 0.1524)
			(layers "F.Cu" "F.Mask" "F.Paste")
			(net "P3V3_STBY")
			(options
				(clearance outline)
				(anchor circle)
			)
			(primitives
				(gr_poly
					(pts
						(arc
							(start 0.3048 -0.2032)
							(mid 0.275042 -0.275042)
							(end 0.2032 -0.3048)
						)
						(arc
							(start -0.2032 -0.3048)
							(mid -0.275042 -0.275042)
							(end -0.3048 -0.2032)
						)
						(arc
							(start -0.3048 0.2032)
							(mid -0.275042 0.275042)
							(end -0.2032 0.3048)
						)
						(arc
							(start 0.2032 0.3048)
							(mid 0.275042 0.275042)
							(end 0.3048 0.2032)
						)
					)
					(width 0)
					(fill yes)
				)
			)
		)
		(pad "2" smd custom
			(at 0 0.4445)
			(size 0.1524 0.1524)
			(layers "F.Cu" "F.Mask" "F.Paste")
			(net "GND")
			(options
				(clearance outline)
				(anchor circle)
			)
			(primitives
				(gr_poly
					(pts
						(arc
							(start 0.3048 -0.2032)
							(mid 0.275042 -0.275042)
							(end 0.2032 -0.3048)
						)
						(arc
							(start -0.2032 -0.3048)
							(mid -0.275042 -0.275042)
							(end -0.3048 -0.2032)
						)
						(arc
							(start -0.3048 0.2032)
							(mid -0.275042 0.275042)
							(end -0.2032 0.3048)
						)
						(arc
							(start 0.2032 0.3048)
							(mid 0.275042 0.275042)
							(end 0.3048 0.2032)
						)
					)
					(width 0)
					(fill yes)
				)
			)
		)
	)
	(footprint ""
		(layer "F.Cu")
		(at 197.821296 -86.372192)
		(property "Reference" "SC1131"
			(at 0 0 0)
			(layer "F.SilkS")
			(hide yes)
			(effects
				(font
					(size 1.27 1.27)
				)
			)
		)
		(property "Value" "SC100U6D3V0MX-2GP"
			(at -0.00254 -4.78536 0)
			(unlocked yes)
			(layer "F.Fab")
			(hide yes)
			(effects
				(font
					(size 1.016 1.016)
					(thickness 0.1524)
				)
			)
		)
		(property "Device Type" "C1210H107"
			(at -0.00254 -6.38048 0)
			(unlocked yes)
			(layer "F.Fab")
			(hide yes)
			(effects
				(font
					(size 1.016 1.016)
					(thickness 0.1524)
				)
			)
		)
		(duplicate_pad_numbers_are_jumpers no)
		(fp_line
			(start -1.5748 -2.3368)
			(end -1.5748 -0.762)
			(stroke
				(width 0.1524)
				(type default)
			)
			(layer "F.SilkS")
		)
		(fp_line
			(start -1.5748 0.762)
			(end -1.5748 2.3368)
			(stroke
				(width 0.1524)
				(type default)
			)
			(layer "F.SilkS")
		)
		(fp_line
			(start -1.5748 2.3368)
			(end 1.5748 2.3368)
			(stroke
				(width 0.1524)
				(type default)
			)
			(layer "F.SilkS")
		)
		(fp_line
			(start 1.5748 -2.3368)
			(end -1.5748 -2.3368)
			(stroke
				(width 0.1524)
				(type default)
			)
			(layer "F.SilkS")
		)
		(fp_line
			(start 1.5748 -0.762)
			(end 1.5748 -2.3368)
			(stroke
				(width 0.1524)
				(type default)
			)
			(layer "F.SilkS")
		)
		(fp_line
			(start 1.5748 2.3368)
			(end 1.5748 0.762)
			(stroke
				(width 0.1524)
				(type default)
			)
			(layer "F.SilkS")
		)
		(fp_rect
			(start -1.651 2.413)
			(end 1.651 -2.413)
			(stroke
				(width 0)
				(type default)
			)
			(fill no)
			(layer "F.CrtYd")
		)
		(fp_poly
			(pts
				(xy 1.651 2.413) (xy 1.651 -2.413) (xy -1.651 -2.413) (xy -1.651 2.413)
			)
			(stroke
				(width 0)
				(type default)
			)
			(fill no)
			(layer "F.Fab")
		)
		(pad "1" smd rect
			(at 0 -1.4732)
			(size 2.794 1.397)
			(layers "F.Cu" "F.Mask" "F.Paste")
			(net "GND")
		)
		(pad "2" smd rect
			(at 0 1.4732)
			(size 2.794 1.397)
			(layers "F.Cu" "F.Mask" "F.Paste")
			(net "GB_VDDH2")
		)
	)
	(footprint ""
		(layer "F.Cu")
		(at 305.435 -184.785)
		(property "Reference" "TP113"
			(at 0 0 0)
			(layer "F.SilkS")
			(hide yes)
			(effects
				(font
					(size 1.27 1.27)
				)
			)
		)
		(property "Value" "TPAD28"
			(at 0.0127 -1.8034 0)
			(unlocked yes)
			(layer "F.Fab")
			(hide yes)
			(effects
				(font
					(size 1.016 1.016)
					(thickness 0.1524)
				)
			)
		)
		(property "Device Type" "TPAD28"
			(at 0.0127 -3.3274 0)
			(unlocked yes)
			(layer "F.Fab")
			(hide yes)
			(effects
				(font
					(size 1.016 1.016)
					(thickness 0.1524)
				)
			)
		)
		(duplicate_pad_numbers_are_jumpers no)
		(fp_poly
			(pts
				(arc
					(start 0.3556 0)
					(mid -0.3556 0)
					(end 0.3556 0)
				)
			)
			(stroke
				(width 0)
				(type default)
			)
			(fill no)
			(layer "F.CrtYd")
		)
		(fp_poly
			(pts
				(arc
					(start 0.6096 0)
					(mid -0.6096 0)
					(end 0.6096 0)
				)
			)
			(stroke
				(width 0)
				(type default)
			)
			(fill no)
			(layer "F.Fab")
		)
		(pad "1" smd circle
			(at 0 0)
			(size 0.7112 0.7112)
			(layers "F.Cu" "F.Mask" "F.Paste")
			(net "TP_BMC_GPIOM6")
		)
	)
	(footprint ""
		(layer "F.Cu")
		(at 179.052982 -24.929338)
		(property "Reference" "TP131"
			(at 0 0 0)
			(layer "F.SilkS")
			(hide yes)
			(effects
				(font
					(size 1.27 1.27)
				)
			)
		)
		(property "Value" "TPAD28"
			(at 0.0127 -1.8034 0)
			(unlocked yes)
			(layer "F.Fab")
			(hide yes)
			(effects
				(font
					(size 1.016 1.016)
					(thickness 0.1524)
				)
			)
		)
		(property "Device Type" "TPAD28"
			(at 0.0127 -3.3274 0)
			(unlocked yes)
			(layer "F.Fab")
			(hide yes)
			(effects
				(font
					(size 1.016 1.016)
					(thickness 0.1524)
				)
			)
		)
		(duplicate_pad_numbers_are_jumpers no)
		(fp_poly
			(pts
				(arc
					(start 0.3556 0)
					(mid -0.3556 0)
					(end 0.3556 0)
				)
			)
			(stroke
				(width 0)
				(type default)
			)
			(fill no)
			(layer "F.CrtYd")
		)
		(fp_poly
			(pts
				(arc
					(start 0.6096 0)
					(mid -0.6096 0)
					(end 0.6096 0)
				)
			)
			(stroke
				(width 0)
				(type default)
			)
			(fill no)
			(layer "F.Fab")
		)
		(pad "1" smd circle
			(at 0 0)
			(size 0.7112 0.7112)
			(layers "F.Cu" "F.Mask" "F.Paste")
			(net "NC_PHY_BMC_INTR_N")
		)
	)
	(footprint ""
		(layer "F.Cu")
		(at 204.597 -92.329)
		(property "Reference" "PG5"
			(at 0 0 0)
			(layer "F.SilkS")
			(hide yes)
			(effects
				(font
					(size 1.27 1.27)
				)
			)
		)
		(property "Value" "GAP-CLOSE-PWR-4-GP"
			(at -2.4638 -0.5461 0)
			(unlocked yes)
			(layer "F.Fab")
			(hide yes)
			(effects
				(font
					(size 1.016 1.016)
					(thickness 0.1524)
				)
			)
		)
		(property "Device Type" "GAP-CLOSE-PWR-4"
			(at -2.4638 -2.0701 0)
			(unlocked yes)
			(layer "F.Fab")
			(hide yes)
			(effects
				(font
					(size 1.016 1.016)
					(thickness 0.1524)
				)
			)
		)
		(duplicate_pad_numbers_are_jumpers no)
		(fp_rect
			(start -0.2794 0.254)
			(end 0.2794 -0.254)
			(stroke
				(width 0)
				(type default)
			)
			(fill no)
			(layer "F.CrtYd")
		)
		(fp_rect
			(start -0.2794 0.254)
			(end 0.2794 -0.254)
			(stroke
				(width 0)
				(type default)
			)
			(fill no)
			(layer "F.Fab")
		)
		(pad "1" smd rect
			(at -0.0635 0)
			(size 0.1778 0.254)
			(layers "F.Cu" "F.Mask" "F.Paste")
			(net "P1V5_E")
		)
		(pad "2" smd rect
			(at 0.0635 0)
			(size 0.1778 0.254)
			(layers "F.Cu" "F.Mask" "F.Paste")
			(net "P1V5_E_CC")
		)
	)
	(footprint ""
		(layer "F.Cu")
		(at 324.358 -182.372)
		(property "Reference" "R5767"
			(at 0 0 0)
			(layer "F.SilkS")
			(hide yes)
			(effects
				(font
					(size 1.27 1.27)
				)
			)
		)
		(property "Value" "1KR2F-3-GP"
			(at 0.064008 -3.993896 0)
			(unlocked yes)
			(layer "F.Fab")
			(hide yes)
			(effects
				(font
					(size 1.016 1.016)
					(thickness 0.1524)
				)
			)
		)
		(property "Device Type" "R402H16"
			(at 0.064008 -5.517896 0)
			(unlocked yes)
			(layer "F.Fab")
			(hide yes)
			(effects
				(font
					(size 1.016 1.016)
					(thickness 0.1524)
				)
			)
		)
		(duplicate_pad_numbers_are_jumpers no)
		(fp_line
			(start -0.508 -0.9398)
			(end -0.508 0.9398)
			(stroke
				(width 0.1524)
				(type default)
			)
			(layer "F.SilkS")
		)
		(fp_line
			(start 0.508 -0.9398)
			(end -0.508 -0.9398)
			(stroke
				(width 0.1524)
				(type default)
			)
			(layer "F.SilkS")
		)
		(fp_rect
			(start -0.508 0.9398)
			(end 0.508 -0.9398)
			(stroke
				(width 0)
				(type default)
			)
			(fill no)
			(layer "F.CrtYd")
		)
		(fp_rect
			(start -0.508 0.9398)
			(end 0.508 -0.9398)
			(stroke
				(width 0)
				(type default)
			)
			(fill no)
			(layer "F.Fab")
		)
		(pad "1" smd custom
			(at 0 -0.4445)
			(size 0.1397 0.1397)
			(layers "F.Cu" "F.Mask" "F.Paste")
			(net "ADC_P1V8_STBY")
			(options
				(clearance outline)
				(anchor circle)
			)
			(primitives
				(gr_poly
					(pts
						(arc
							(start -0.1778 -0.2794)
							(mid -0.249642 -0.249642)
							(end -0.2794 -0.1778)
						)
						(arc
							(start -0.2794 0.1778)
							(mid -0.249642 0.249642)
							(end -0.1778 0.2794)
						)
						(arc
							(start 0.1778 0.2794)
							(mid 0.249642 0.249642)
							(end 0.2794 0.1778)
						)
						(arc
							(start 0.2794 -0.1778)
							(mid 0.249642 -0.249642)
							(end 0.1778 -0.2794)
						)
					)
					(width 0)
					(fill yes)
				)
			)
		)
		(pad "2" smd custom
			(at 0 0.4445)
			(size 0.1397 0.1397)
			(layers "F.Cu" "F.Mask" "F.Paste")
			(net "GND")
			(options
				(clearance outline)
				(anchor circle)
			)
			(primitives
				(gr_poly
					(pts
						(arc
							(start -0.1778 -0.2794)
							(mid -0.249642 -0.249642)
							(end -0.2794 -0.1778)
						)
						(arc
							(start -0.2794 0.1778)
							(mid -0.249642 0.249642)
							(end -0.1778 0.2794)
						)
						(arc
							(start 0.1778 0.2794)
							(mid 0.249642 0.249642)
							(end 0.2794 0.1778)
						)
						(arc
							(start 0.2794 -0.1778)
							(mid 0.249642 -0.249642)
							(end 0.1778 -0.2794)
						)
					)
					(width 0)
					(fill yes)
				)
			)
		)
	)
	(footprint ""
		(layer "F.Cu")
		(at 171.226988 -32.621728 180)
		(property "Reference" "C236"
			(at 0 0 180)
			(layer "F.SilkS")
			(hide yes)
			(effects
				(font
					(size 1.27 1.27)
				)
			)
		)
		(property "Value" "SCD1U16V2KX-3GP"
			(at 1.1811 -2.7051 180)
			(unlocked yes)
			(layer "F.Fab")
			(hide yes)
			(effects
				(font
					(size 1.016 1.016)
					(thickness 0.1524)
				)
			)
		)
		(property "Device Type" "C402H22"
			(at 1.1811 -4.2291 180)
			(unlocked yes)
			(layer "F.Fab")
			(hide yes)
			(effects
				(font
					(size 1.016 1.016)
					(thickness 0.1524)
				)
			)
		)
		(duplicate_pad_numbers_are_jumpers no)
		(fp_rect
			(start -0.4318 0.9525)
			(end 0.4318 -0.9525)
			(stroke
				(width 0)
				(type default)
			)
			(fill no)
			(layer "F.CrtYd")
		)
		(fp_rect
			(start -0.4318 0.9525)
			(end 0.4318 -0.9525)
			(stroke
				(width 0)
				(type default)
			)
			(fill no)
			(layer "F.Fab")
		)
		(pad "1" smd custom
			(at 0 -0.4445 180)
			(size 0.1524 0.1524)
			(layers "F.Cu" "F.Mask" "F.Paste")
			(net "MOD_IMC_FAB_D_COP")
			(options
				(clearance outline)
				(anchor circle)
			)
			(primitives
				(gr_poly
					(pts
						(arc
							(start 0.3048 -0.2032)
							(mid 0.275042 -0.275042)
							(end 0.2032 -0.3048)
						)
						(arc
							(start -0.2032 -0.3048)
							(mid -0.275042 -0.275042)
							(end -0.3048 -0.2032)
						)
						(arc
							(start -0.3048 0.2032)
							(mid -0.275042 0.275042)
							(end -0.2032 0.3048)
						)
						(arc
							(start 0.2032 0.3048)
							(mid 0.275042 0.275042)
							(end 0.3048 0.2032)
						)
					)
					(width 0)
					(fill yes)
				)
			)
		)
		(pad "2" smd custom
			(at 0 0.4445 180)
			(size 0.1524 0.1524)
			(layers "F.Cu" "F.Mask" "F.Paste")
			(net "GND")
			(options
				(clearance outline)
				(anchor circle)
			)
			(primitives
				(gr_poly
					(pts
						(arc
							(start 0.3048 -0.2032)
							(mid 0.275042 -0.275042)
							(end 0.2032 -0.3048)
						)
						(arc
							(start -0.2032 -0.3048)
							(mid -0.275042 -0.275042)
							(end -0.3048 -0.2032)
						)
						(arc
							(start -0.3048 0.2032)
							(mid -0.275042 0.275042)
							(end -0.2032 0.3048)
						)
						(arc
							(start 0.2032 0.3048)
							(mid 0.275042 0.275042)
							(end 0.3048 0.2032)
						)
					)
					(width 0)
					(fill yes)
				)
			)
		)
	)
)
